(kicad_pcb
	(version 20260206)
	(generator "pcbnew")
	(generator_version "10.0")
	(general
		(thickness 1.6)
		(legacy_teardrops no)
	)
	(paper "A4")
	(title_block
		(title "01162023_DA0F0TEBIF0_F0T_Expander_BD_F_brd_V02_OCP.brd")
		(comment 1 "Grand Teton / footprints 4477-4483 of 9728")
	)
	(layers
		(0 "F.Cu" signal "TOP")
		(4 "In1.Cu" signal "GND")
		(6 "In2.Cu" signal "VCC")
		(8 "In3.Cu" signal "VCC1")
		(10 "In4.Cu" signal "GND1")
		(12 "In5.Cu" signal "IN1")
		(14 "In6.Cu" signal "GND2")
		(16 "In7.Cu" signal "IN2")
		(18 "In8.Cu" signal "GND3")
		(20 "In9.Cu" signal "IN3")
		(22 "In10.Cu" signal "GND4")
		(24 "In11.Cu" signal "IN4")
		(26 "In12.Cu" signal "GND5")
		(28 "In13.Cu" signal "IN5")
		(30 "In14.Cu" signal "GND6")
		(32 "In15.Cu" signal "IN6")
		(34 "In16.Cu" signal "GND7")
		(2 "B.Cu" signal "BOTTOM")
		(9 "F.Adhes" user "F.Adhesive")
		(11 "B.Adhes" user "B.Adhesive")
		(13 "F.Paste" user "Package Geometry/Pastemask Top")
		(15 "B.Paste" user "Package Geometry/Pastemask Bottom")
		(5 "F.SilkS" user "Ref Des/Silkscreen Top")
		(7 "B.SilkS" user "Ref Des/Silkscreen Bottom")
		(1 "F.Mask" user "Board Geometry/Soldermask Top")
		(3 "B.Mask" user "Board Geometry/Soldermask Bottom")
		(17 "Dwgs.User" user "User.Drawings")
		(19 "Cmts.User" user "User.Comments")
		(21 "Eco1.User" user "User.Eco1")
		(23 "Eco2.User" user "User.Eco2")
		(25 "Edge.Cuts" user "Board Geometry/Outline")
		(27 "Margin" user)
		(31 "F.CrtYd" user "Package Geometry/Place Bound Top")
		(29 "B.CrtYd" user "Package Geometry/Place Bound Bottom")
		(35 "F.Fab" user "Ref Des/Assembly Top")
		(33 "B.Fab" user "Ref Des/Assembly Bottom")
	)
	(footprint ""
		(layer "F.Cu")
		(at 156.698442 -250.070874 -90)
		(property "Reference" "R1270"
			(at 0 0 270)
			(layer "F.SilkS")
			(hide yes)
			(effects
				(font
					(size 1.27 1.27)
				)
			)
		)
		(property "Value" ""
			(at 0 0 270)
			(layer "F.Fab")
			(effects
				(font
					(size 1.27 1.27)
				)
			)
		)
		(duplicate_pad_numbers_are_jumpers no)
		(fp_line
			(start -0.7874 0.4064)
			(end -0.7874 -0.4064)
			(stroke
				(width 0.1524)
				(type default)
			)
			(layer "F.SilkS")
		)
		(fp_line
			(start 0.7874 0.4064)
			(end -0.7874 0.4064)
			(stroke
				(width 0.1524)
				(type default)
			)
			(layer "F.SilkS")
		)
		(fp_line
			(start -0.7874 -0.4064)
			(end 0.7874 -0.4064)
			(stroke
				(width 0.1524)
				(type default)
			)
			(layer "F.SilkS")
		)
		(fp_line
			(start 0.7874 -0.4064)
			(end 0.7874 0.4064)
			(stroke
				(width 0.1524)
				(type default)
			)
			(layer "F.SilkS")
		)
		(fp_line
			(start -0.67945 0.3048)
			(end -0.67945 -0.305054)
			(stroke
				(width 0.1)
				(type default)
			)
			(layer "F.Fab")
		)
		(fp_line
			(start -0.12065 0.3048)
			(end -0.67945 0.3048)
			(stroke
				(width 0.1)
				(type default)
			)
			(layer "F.Fab")
		)
		(fp_line
			(start 0.120396 0.3048)
			(end 0.120396 0.2794)
			(stroke
				(width 0.1)
				(type default)
			)
			(layer "F.Fab")
		)
		(fp_line
			(start 0.67945 0.3048)
			(end 0.120396 0.3048)
			(stroke
				(width 0.1)
				(type default)
			)
			(layer "F.Fab")
		)
		(fp_line
			(start -0.12065 0.2794)
			(end -0.12065 0.3048)
			(stroke
				(width 0.1)
				(type default)
			)
			(layer "F.Fab")
		)
		(fp_line
			(start 0.120396 0.2794)
			(end -0.12065 0.2794)
			(stroke
				(width 0.1)
				(type default)
			)
			(layer "F.Fab")
		)
		(fp_line
			(start -0.12065 -0.2794)
			(end 0.12065 -0.2794)
			(stroke
				(width 0.1)
				(type default)
			)
			(layer "F.Fab")
		)
		(fp_line
			(start 0.12065 -0.2794)
			(end 0.12065 -0.3048)
			(stroke
				(width 0.1)
				(type default)
			)
			(layer "F.Fab")
		)
		(fp_line
			(start 0.12065 -0.3048)
			(end 0.67945 -0.3048)
			(stroke
				(width 0.1)
				(type default)
			)
			(layer "F.Fab")
		)
		(fp_line
			(start 0.67945 -0.3048)
			(end 0.67945 0.3048)
			(stroke
				(width 0.1)
				(type default)
			)
			(layer "F.Fab")
		)
		(fp_line
			(start -0.67945 -0.305054)
			(end -0.12065 -0.305054)
			(stroke
				(width 0.1)
				(type default)
			)
			(layer "F.Fab")
		)
		(fp_line
			(start -0.12065 -0.305054)
			(end -0.12065 -0.2794)
			(stroke
				(width 0.1)
				(type default)
			)
			(layer "F.Fab")
		)
		(pad "1" smd circle
			(at -0.40005 0 270)
			(size 0 0)
			(layers "F.Cu" "F.Mask" "F.Paste")
			(net "PEX1_MODE_SEL1")
		)
		(pad "2" smd circle
			(at 0.40005 0 270)
			(size 0 0)
			(layers "F.Cu" "F.Mask" "F.Paste")
			(net "P1V8_PEX")
		)
	)
	(footprint ""
		(layer "F.Cu")
		(at 271.480534 -99.288854)
		(property "Reference" "C485"
			(at 0 0 0)
			(layer "F.SilkS")
			(hide yes)
			(effects
				(font
					(size 1.27 1.27)
				)
			)
		)
		(property "Value" ""
			(at 0 0 0)
			(layer "F.Fab")
			(effects
				(font
					(size 1.27 1.27)
				)
			)
		)
		(duplicate_pad_numbers_are_jumpers no)
		(fp_line
			(start -0.299974 -0.150114)
			(end 0.299974 -0.150114)
			(stroke
				(width 0.1)
				(type default)
			)
			(layer "F.Fab")
		)
		(fp_line
			(start -0.299974 0.150114)
			(end -0.299974 -0.150114)
			(stroke
				(width 0.1)
				(type default)
			)
			(layer "F.Fab")
		)
		(fp_line
			(start 0.299974 -0.150114)
			(end 0.299974 0.150114)
			(stroke
				(width 0.1)
				(type default)
			)
			(layer "F.Fab")
		)
		(fp_line
			(start 0.299974 0.150114)
			(end -0.299974 0.150114)
			(stroke
				(width 0.1)
				(type default)
			)
			(layer "F.Fab")
		)
		(pad "1" smd rect
			(at -0.2667 0)
			(size 0.3048 0.381)
			(layers "F.Cu" "F.Mask" "F.Paste")
			(net "P5E_PEX2_STN1_TX_DP<16>")
		)
		(pad "2" smd rect
			(at 0.2667 0)
			(size 0.3048 0.381)
			(layers "F.Cu" "F.Mask" "F.Paste")
			(net "P5E_PEX2_STN1_TX_C_DP<16>")
		)
	)
	(footprint ""
		(layer "F.Cu")
		(at 150.2791 -59.577986 -90)
		(property "Reference" "R889"
			(at 0 0 270)
			(layer "F.SilkS")
			(hide yes)
			(effects
				(font
					(size 1.27 1.27)
				)
			)
		)
		(property "Value" ""
			(at 0 0 270)
			(layer "F.Fab")
			(effects
				(font
					(size 1.27 1.27)
				)
			)
		)
		(duplicate_pad_numbers_are_jumpers no)
		(fp_line
			(start -0.7874 0.4064)
			(end -0.7874 -0.4064)
			(stroke
				(width 0.1524)
				(type default)
			)
			(layer "F.SilkS")
		)
		(fp_line
			(start 0.7874 0.4064)
			(end -0.7874 0.4064)
			(stroke
				(width 0.1524)
				(type default)
			)
			(layer "F.SilkS")
		)
		(fp_line
			(start -0.7874 -0.4064)
			(end 0.7874 -0.4064)
			(stroke
				(width 0.1524)
				(type default)
			)
			(layer "F.SilkS")
		)
		(fp_line
			(start 0.7874 -0.4064)
			(end 0.7874 0.4064)
			(stroke
				(width 0.1524)
				(type default)
			)
			(layer "F.SilkS")
		)
		(fp_line
			(start -0.67945 0.3048)
			(end -0.67945 -0.305054)
			(stroke
				(width 0.1)
				(type default)
			)
			(layer "F.Fab")
		)
		(fp_line
			(start -0.12065 0.3048)
			(end -0.67945 0.3048)
			(stroke
				(width 0.1)
				(type default)
			)
			(layer "F.Fab")
		)
		(fp_line
			(start 0.120396 0.3048)
			(end 0.120396 0.2794)
			(stroke
				(width 0.1)
				(type default)
			)
			(layer "F.Fab")
		)
		(fp_line
			(start 0.67945 0.3048)
			(end 0.120396 0.3048)
			(stroke
				(width 0.1)
				(type default)
			)
			(layer "F.Fab")
		)
		(fp_line
			(start -0.12065 0.2794)
			(end -0.12065 0.3048)
			(stroke
				(width 0.1)
				(type default)
			)
			(layer "F.Fab")
		)
		(fp_line
			(start 0.120396 0.2794)
			(end -0.12065 0.2794)
			(stroke
				(width 0.1)
				(type default)
			)
			(layer "F.Fab")
		)
		(fp_line
			(start -0.12065 -0.2794)
			(end 0.12065 -0.2794)
			(stroke
				(width 0.1)
				(type default)
			)
			(layer "F.Fab")
		)
		(fp_line
			(start 0.12065 -0.2794)
			(end 0.12065 -0.3048)
			(stroke
				(width 0.1)
				(type default)
			)
			(layer "F.Fab")
		)
		(fp_line
			(start 0.12065 -0.3048)
			(end 0.67945 -0.3048)
			(stroke
				(width 0.1)
				(type default)
			)
			(layer "F.Fab")
		)
		(fp_line
			(start 0.67945 -0.3048)
			(end 0.67945 0.3048)
			(stroke
				(width 0.1)
				(type default)
			)
			(layer "F.Fab")
		)
		(fp_line
			(start -0.67945 -0.305054)
			(end -0.12065 -0.305054)
			(stroke
				(width 0.1)
				(type default)
			)
			(layer "F.Fab")
		)
		(fp_line
			(start -0.12065 -0.305054)
			(end -0.12065 -0.2794)
			(stroke
				(width 0.1)
				(type default)
			)
			(layer "F.Fab")
		)
		(pad "1" smd circle
			(at -0.40005 0 270)
			(size 0 0)
			(layers "F.Cu" "F.Mask" "F.Paste")
			(net "P3V3_SSD5")
		)
		(pad "2" smd circle
			(at 0.40005 0 270)
			(size 0 0)
			(layers "F.Cu" "F.Mask" "F.Paste")
			(net "PWRGD_P3V3_SSD5")
		)
	)
	(footprint ""
		(layer "F.Cu")
		(at 260.606286 -252.356874 -90)
		(property "Reference" "R1354"
			(at 0 0 270)
			(layer "F.SilkS")
			(hide yes)
			(effects
				(font
					(size 1.27 1.27)
				)
			)
		)
		(property "Value" ""
			(at 0 0 270)
			(layer "F.Fab")
			(effects
				(font
					(size 1.27 1.27)
				)
			)
		)
		(duplicate_pad_numbers_are_jumpers no)
		(fp_line
			(start -0.7874 0.4064)
			(end -0.7874 -0.4064)
			(stroke
				(width 0.1524)
				(type default)
			)
			(layer "F.SilkS")
		)
		(fp_line
			(start 0.7874 0.4064)
			(end -0.7874 0.4064)
			(stroke
				(width 0.1524)
				(type default)
			)
			(layer "F.SilkS")
		)
		(fp_line
			(start -0.7874 -0.4064)
			(end 0.7874 -0.4064)
			(stroke
				(width 0.1524)
				(type default)
			)
			(layer "F.SilkS")
		)
		(fp_line
			(start 0.7874 -0.4064)
			(end 0.7874 0.4064)
			(stroke
				(width 0.1524)
				(type default)
			)
			(layer "F.SilkS")
		)
		(fp_line
			(start -0.67945 0.3048)
			(end -0.67945 -0.305054)
			(stroke
				(width 0.1)
				(type default)
			)
			(layer "F.Fab")
		)
		(fp_line
			(start -0.12065 0.3048)
			(end -0.67945 0.3048)
			(stroke
				(width 0.1)
				(type default)
			)
			(layer "F.Fab")
		)
		(fp_line
			(start 0.120396 0.3048)
			(end 0.120396 0.2794)
			(stroke
				(width 0.1)
				(type default)
			)
			(layer "F.Fab")
		)
		(fp_line
			(start 0.67945 0.3048)
			(end 0.120396 0.3048)
			(stroke
				(width 0.1)
				(type default)
			)
			(layer "F.Fab")
		)
		(fp_line
			(start -0.12065 0.2794)
			(end -0.12065 0.3048)
			(stroke
				(width 0.1)
				(type default)
			)
			(layer "F.Fab")
		)
		(fp_line
			(start 0.120396 0.2794)
			(end -0.12065 0.2794)
			(stroke
				(width 0.1)
				(type default)
			)
			(layer "F.Fab")
		)
		(fp_line
			(start -0.12065 -0.2794)
			(end 0.12065 -0.2794)
			(stroke
				(width 0.1)
				(type default)
			)
			(layer "F.Fab")
		)
		(fp_line
			(start 0.12065 -0.2794)
			(end 0.12065 -0.3048)
			(stroke
				(width 0.1)
				(type default)
			)
			(layer "F.Fab")
		)
		(fp_line
			(start 0.12065 -0.3048)
			(end 0.67945 -0.3048)
			(stroke
				(width 0.1)
				(type default)
			)
			(layer "F.Fab")
		)
		(fp_line
			(start 0.67945 -0.3048)
			(end 0.67945 0.3048)
			(stroke
				(width 0.1)
				(type default)
			)
			(layer "F.Fab")
		)
		(fp_line
			(start -0.67945 -0.305054)
			(end -0.12065 -0.305054)
			(stroke
				(width 0.1)
				(type default)
			)
			(layer "F.Fab")
		)
		(fp_line
			(start -0.12065 -0.305054)
			(end -0.12065 -0.2794)
			(stroke
				(width 0.1)
				(type default)
			)
			(layer "F.Fab")
		)
		(pad "1" smd circle
			(at -0.40005 0 270)
			(size 0 0)
			(layers "F.Cu" "F.Mask" "F.Paste")
			(net "GND")
		)
		(pad "2" smd circle
			(at 0.40005 0 270)
			(size 0 0)
			(layers "F.Cu" "F.Mask" "F.Paste")
			(net "PEX2_DBG_MODE3")
		)
	)
	(footprint ""
		(layer "F.Cu")
		(at 490.661452 -554.392338 180)
		(property "Reference" "SCREW_SSD6_1"
			(at -5.207 -1.402334 0)
			(unlocked yes)
			(layer "B.SilkS")
			(effects
				(font
					(size 0.7874 0.5842)
					(thickness 0.1524)
				)
				(justify mirror)
			)
		)
		(property "Value" ""
			(at 0 0 180)
			(layer "F.Fab")
			(effects
				(font
					(size 1.27 1.27)
				)
			)
		)
		(duplicate_pad_numbers_are_jumpers no)
		(pad "1" thru_hole circle
			(at 0 0 180)
			(size 0.4572 0.4572)
			(drill 0.2032)
			(layers "*.Cu" "*.Mask")
			(remove_unused_layers no)
			(net "Net_9132")
			(clearance 0.127)
			(thermal_gap 0.127)
			(padstack
				(mode front_inner_back)
				(layer "Inner"
					(shape circle)
					(size 0.4572 0.4572)
					(clearance 0.127)
				)
				(layer "B.Cu"
					(shape circle)
					(size 0.508 0.508)
					(clearance 0.1016)
				)
			)
		)
	)
	(footprint ""
		(layer "F.Cu")
		(at 255.32842 -260.807708 90)
		(property "Reference" "R5801"
			(at 0 0 90)
			(layer "F.SilkS")
			(hide yes)
			(effects
				(font
					(size 1.27 1.27)
				)
			)
		)
		(property "Value" ""
			(at 0 0 90)
			(layer "F.Fab")
			(effects
				(font
					(size 1.27 1.27)
				)
			)
		)
		(duplicate_pad_numbers_are_jumpers no)
		(fp_line
			(start 0.7874 -0.4064)
			(end 0.7874 0.4064)
			(stroke
				(width 0.1524)
				(type default)
			)
			(layer "F.SilkS")
		)
		(fp_line
			(start -0.7874 -0.4064)
			(end 0.7874 -0.4064)
			(stroke
				(width 0.1524)
				(type default)
			)
			(layer "F.SilkS")
		)
		(fp_line
			(start 0.7874 0.4064)
			(end -0.7874 0.4064)
			(stroke
				(width 0.1524)
				(type default)
			)
			(layer "F.SilkS")
		)
		(fp_line
			(start -0.7874 0.4064)
			(end -0.7874 -0.4064)
			(stroke
				(width 0.1524)
				(type default)
			)
			(layer "F.SilkS")
		)
		(fp_line
			(start -0.12065 -0.305054)
			(end -0.12065 -0.2794)
			(stroke
				(width 0.1)
				(type default)
			)
			(layer "F.Fab")
		)
		(fp_line
			(start -0.67945 -0.305054)
			(end -0.12065 -0.305054)
			(stroke
				(width 0.1)
				(type default)
			)
			(layer "F.Fab")
		)
		(fp_line
			(start 0.67945 -0.3048)
			(end 0.67945 0.3048)
			(stroke
				(width 0.1)
				(type default)
			)
			(layer "F.Fab")
		)
		(fp_line
			(start 0.12065 -0.3048)
			(end 0.67945 -0.3048)
			(stroke
				(width 0.1)
				(type default)
			)
			(layer "F.Fab")
		)
		(fp_line
			(start 0.12065 -0.2794)
			(end 0.12065 -0.3048)
			(stroke
				(width 0.1)
				(type default)
			)
			(layer "F.Fab")
		)
		(fp_line
			(start -0.12065 -0.2794)
			(end 0.12065 -0.2794)
			(stroke
				(width 0.1)
				(type default)
			)
			(layer "F.Fab")
		)
		(fp_line
			(start 0.120396 0.2794)
			(end -0.12065 0.2794)
			(stroke
				(width 0.1)
				(type default)
			)
			(layer "F.Fab")
		)
		(fp_line
			(start -0.12065 0.2794)
			(end -0.12065 0.3048)
			(stroke
				(width 0.1)
				(type default)
			)
			(layer "F.Fab")
		)
		(fp_line
			(start 0.67945 0.3048)
			(end 0.120396 0.3048)
			(stroke
				(width 0.1)
				(type default)
			)
			(layer "F.Fab")
		)
		(fp_line
			(start 0.120396 0.3048)
			(end 0.120396 0.2794)
			(stroke
				(width 0.1)
				(type default)
			)
			(layer "F.Fab")
		)
		(fp_line
			(start -0.12065 0.3048)
			(end -0.67945 0.3048)
			(stroke
				(width 0.1)
				(type default)
			)
			(layer "F.Fab")
		)
		(fp_line
			(start -0.67945 0.3048)
			(end -0.67945 -0.305054)
			(stroke
				(width 0.1)
				(type default)
			)
			(layer "F.Fab")
		)
		(pad "1" smd circle
			(at -0.40005 0 90)
			(size 0 0)
			(layers "F.Cu" "F.Mask" "F.Paste")
			(net "PEX2_SYS_ERR_N_G")
		)
		(pad "2" smd circle
			(at 0.40005 0 90)
			(size 0 0)
			(layers "F.Cu" "F.Mask" "F.Paste")
			(net "PEX2_SYS_ERR_FPGA")
		)
	)
	(footprint ""
		(layer "F.Cu")
		(at 196.375528 -368.26698 180)
		(property "Reference" "R6249"
			(at 0 0 180)
			(layer "F.SilkS")
			(hide yes)
			(effects
				(font
					(size 1.27 1.27)
				)
			)
		)
		(property "Value" ""
			(at 0 0 180)
			(layer "F.Fab")
			(effects
				(font
					(size 1.27 1.27)
				)
			)
		)
		(duplicate_pad_numbers_are_jumpers no)
		(fp_line
			(start 0.7874 0.4064)
			(end -0.7874 0.4064)
			(stroke
				(width 0.1524)
				(type default)
			)
			(layer "F.SilkS")
		)
		(fp_line
			(start 0.7874 -0.4064)
			(end 0.7874 0.4064)
			(stroke
				(width 0.1524)
				(type default)
			)
			(layer "F.SilkS")
		)
		(fp_line
			(start -0.7874 0.4064)
			(end -0.7874 -0.4064)
			(stroke
				(width 0.1524)
				(type default)
			)
			(layer "F.SilkS")
		)
		(fp_line
			(start -0.7874 -0.4064)
			(end 0.7874 -0.4064)
			(stroke
				(width 0.1524)
				(type default)
			)
			(layer "F.SilkS")
		)
		(fp_line
			(start 0.67945 0.3048)
			(end 0.120396 0.3048)
			(stroke
				(width 0.1)
				(type default)
			)
			(layer "F.Fab")
		)
		(fp_line
			(start 0.67945 -0.3048)
			(end 0.67945 0.3048)
			(stroke
				(width 0.1)
				(type default)
			)
			(layer "F.Fab")
		)
		(fp_line
			(start 0.12065 -0.2794)
			(end 0.12065 -0.3048)
			(stroke
				(width 0.1)
				(type default)
			)
			(layer "F.Fab")
		)
		(fp_line
			(start 0.12065 -0.3048)
			(end 0.67945 -0.3048)
			(stroke
				(width 0.1)
				(type default)
			)
			(layer "F.Fab")
		)
		(fp_line
			(start 0.120396 0.3048)
			(end 0.120396 0.2794)
			(stroke
				(width 0.1)
				(type default)
			)
			(layer "F.Fab")
		)
		(fp_line
			(start 0.120396 0.2794)
			(end -0.12065 0.2794)
			(stroke
				(width 0.1)
				(type default)
			)
			(layer "F.Fab")
		)
		(fp_line
			(start -0.12065 0.3048)
			(end -0.67945 0.3048)
			(stroke
				(width 0.1)
				(type default)
			)
			(layer "F.Fab")
		)
		(fp_line
			(start -0.12065 0.2794)
			(end -0.12065 0.3048)
			(stroke
				(width 0.1)
				(type default)
			)
			(layer "F.Fab")
		)
		(fp_line
			(start -0.12065 -0.2794)
			(end 0.12065 -0.2794)
			(stroke
				(width 0.1)
				(type default)
			)
			(layer "F.Fab")
		)
		(fp_line
			(start -0.12065 -0.305054)
			(end -0.12065 -0.2794)
			(stroke
				(width 0.1)
				(type default)
			)
			(layer "F.Fab")
		)
		(fp_line
			(start -0.67945 0.3048)
			(end -0.67945 -0.305054)
			(stroke
				(width 0.1)
				(type default)
			)
			(layer "F.Fab")
		)
		(fp_line
			(start -0.67945 -0.305054)
			(end -0.12065 -0.305054)
			(stroke
				(width 0.1)
				(type default)
			)
			(layer "F.Fab")
		)
		(pad "1" smd circle
			(at -0.40005 0 180)
			(size 0 0)
			(layers "F.Cu" "F.Mask" "F.Paste")
			(net "FM_HSC_PWROK")
		)
		(pad "2" smd circle
			(at 0.40005 0 180)
			(size 0 0)
			(layers "F.Cu" "F.Mask" "F.Paste")
			(net "P12V_AUX")
		)
	)
)
